# T6G (Grand Teton) — schematic netlist excerpt (pin names and nets, part order shuffled) for the footprints in the layout excerpt that follows; sources: Cadence DE-HDL packaged netlist, KiCad conversion of 04192023_DAF0TMB3IC0_F0TG_MB_C_brd_V02_OCP.brd

PR1133  Q_RES  2K 0.1% CHIP  pkg 0402LF  page 262 : A = HSC_IMON ; B = AGND_HSC
C1824  Q_CAP  0.1UF 25V 10% X7R  pkg 0402  page 139 : A = P3V3_AUX ; B = GND

(kicad_pcb
	(version 20260206)
	(generator "pcbnew")
	(generator_version "10.0")
	(general
		(thickness 1.6)
		(legacy_teardrops no)
	)
	(paper "A4")
	(title_block
		(title "04192023_DAF0TMB3IC0_F0TG_MB_C_brd_V02_OCP.brd")
		(comment 1 "Grand Teton / footprints 3432-3433 of 8354")
	)
	(layers
		(0 "F.Cu" signal "TOP")
		(4 "In1.Cu" signal "GND")
		(6 "In2.Cu" signal "IN1")
		(8 "In3.Cu" signal "GND1")
		(10 "In4.Cu" signal "IN2")
		(12 "In5.Cu" signal "GND2")
		(14 "In6.Cu" signal "IN3")
		(16 "In7.Cu" signal "GND3")
		(18 "In8.Cu" signal "VCC")
		(20 "In9.Cu" signal "VCC1")
		(22 "In10.Cu" signal "GND4")
		(24 "In11.Cu" signal "IN4")
		(26 "In12.Cu" signal "GND5")
		(28 "In13.Cu" signal "IN5")
		(30 "In14.Cu" signal "GND6")
		(32 "In15.Cu" signal "IN6")
		(34 "In16.Cu" signal "GND7")
		(2 "B.Cu" signal "BOTTOM")
		(9 "F.Adhes" user "F.Adhesive")
		(11 "B.Adhes" user "B.Adhesive")
		(13 "F.Paste" user "Package Geometry/Pastemask Top")
		(15 "B.Paste" user "Package Geometry/Pastemask Bottom")
		(5 "F.SilkS" user "Ref Des/Silkscreen Top")
		(7 "B.SilkS" user "Ref Des/Silkscreen Bottom")
		(1 "F.Mask" user "Board Geometry/Soldermask Top")
		(3 "B.Mask" user "Board Geometry/Soldermask Bottom")
		(17 "Dwgs.User" user "User.Drawings")
		(19 "Cmts.User" user "User.Comments")
		(21 "Eco1.User" user "User.Eco1")
		(23 "Eco2.User" user "User.Eco2")
		(25 "Edge.Cuts" user "Board Geometry/Outline")
		(27 "Margin" user)
		(31 "F.CrtYd" user "Package Geometry/Place Bound Top")
		(29 "B.CrtYd" user "Package Geometry/Place Bound Bottom")
		(35 "F.Fab" user "Ref Des/Assembly Top")
		(33 "B.Fab" user "Ref Des/Assembly Bottom")
	)
	(footprint ""
		(layer "F.Cu")
		(at 98.550222 -36.305998)
		(property "Reference" "C1824"
			(at 0 0 0)
			(layer "F.SilkS")
			(hide yes)
			(effects
				(font
					(size 1.27 1.27)
				)
			)
		)
		(property "Value" ""
			(at 0 0 0)
			(layer "F.Fab")
			(effects
				(font
					(size 1.27 1.27)
				)
			)
		)
		(duplicate_pad_numbers_are_jumpers no)
		(fp_line
			(start -0.7874 -0.4064)
			(end 0.7874 -0.4064)
			(stroke
				(width 0.1524)
				(type default)
			)
			(layer "F.SilkS")
		)
		(fp_line
			(start -0.7874 0.4064)
			(end -0.7874 -0.4064)
			(stroke
				(width 0.1524)
				(type default)
			)
			(layer "F.SilkS")
		)
		(fp_line
			(start 0.7874 -0.4064)
			(end 0.7874 0.4064)
			(stroke
				(width 0.1524)
				(type default)
			)
			(layer "F.SilkS")
		)
		(fp_line
			(start 0.7874 0.4064)
			(end -0.7874 0.4064)
			(stroke
				(width 0.1524)
				(type default)
			)
			(layer "F.SilkS")
		)
		(fp_line
			(start -0.67945 -0.305054)
			(end -0.12065 -0.305054)
			(stroke
				(width 0.1)
				(type default)
			)
			(layer "F.Fab")
		)
		(fp_line
			(start -0.67945 0.3048)
			(end -0.67945 -0.305054)
			(stroke
				(width 0.1)
				(type default)
			)
			(layer "F.Fab")
		)
		(fp_line
			(start -0.12065 -0.305054)
			(end -0.12065 -0.2794)
			(stroke
				(width 0.1)
				(type default)
			)
			(layer "F.Fab")
		)
		(fp_line
			(start -0.12065 -0.2794)
			(end 0.12065 -0.2794)
			(stroke
				(width 0.1)
				(type default)
			)
			(layer "F.Fab")
		)
		(fp_line
			(start -0.12065 0.2794)
			(end -0.12065 0.3048)
			(stroke
				(width 0.1)
				(type default)
			)
			(layer "F.Fab")
		)
		(fp_line
			(start -0.12065 0.3048)
			(end -0.67945 0.3048)
			(stroke
				(width 0.1)
				(type default)
			)
			(layer "F.Fab")
		)
		(fp_line
			(start 0.120396 0.2794)
			(end -0.12065 0.2794)
			(stroke
				(width 0.1)
				(type default)
			)
			(layer "F.Fab")
		)
		(fp_line
			(start 0.120396 0.3048)
			(end 0.120396 0.2794)
			(stroke
				(width 0.1)
				(type default)
			)
			(layer "F.Fab")
		)
		(fp_line
			(start 0.12065 -0.3048)
			(end 0.67945 -0.3048)
			(stroke
				(width 0.1)
				(type default)
			)
			(layer "F.Fab")
		)
		(fp_line
			(start 0.12065 -0.2794)
			(end 0.12065 -0.3048)
			(stroke
				(width 0.1)
				(type default)
			)
			(layer "F.Fab")
		)
		(fp_line
			(start 0.67945 -0.3048)
			(end 0.67945 0.3048)
			(stroke
				(width 0.1)
				(type default)
			)
			(layer "F.Fab")
		)
		(fp_line
			(start 0.67945 0.3048)
			(end 0.120396 0.3048)
			(stroke
				(width 0.1)
				(type default)
			)
			(layer "F.Fab")
		)
		(pad "1" smd circle
			(at -0.40005 0)
			(size 0 0)
			(layers "F.Cu" "F.Mask" "F.Paste")
			(net "P3V3_AUX")
		)
		(pad "2" smd circle
			(at 0.40005 0)
			(size 0 0)
			(layers "F.Cu" "F.Mask" "F.Paste")
			(net "GND")
		)
	)
	(footprint ""
		(layer "F.Cu")
		(at 178.71694 -398.404842 180)
		(property "Reference" "PR1133"
			(at 0 0 180)
			(layer "F.SilkS")
			(hide yes)
			(effects
				(font
					(size 1.27 1.27)
				)
			)
		)
		(property "Value" ""
			(at 0 0 180)
			(layer "F.Fab")
			(effects
				(font
					(size 1.27 1.27)
				)
			)
		)
		(duplicate_pad_numbers_are_jumpers no)
		(fp_line
			(start 0.7874 0.4064)
			(end -0.7874 0.4064)
			(stroke
				(width 0.1524)
				(type default)
			)
			(layer "F.SilkS")
		)
		(fp_line
			(start 0.7874 -0.4064)
			(end 0.7874 0.4064)
			(stroke
				(width 0.1524)
				(type default)
			)
			(layer "F.SilkS")
		)
		(fp_line
			(start -0.7874 0.4064)
			(end -0.7874 -0.4064)
			(stroke
				(width 0.1524)
				(type default)
			)
			(layer "F.SilkS")
		)
		(fp_line
			(start -0.7874 -0.4064)
			(end 0.7874 -0.4064)
			(stroke
				(width 0.1524)
				(type default)
			)
			(layer "F.SilkS")
		)
		(fp_line
			(start 0.67945 0.3048)
			(end 0.120396 0.3048)
			(stroke
				(width 0.1)
				(type default)
			)
			(layer "F.Fab")
		)
		(fp_line
			(start 0.67945 -0.3048)
			(end 0.67945 0.3048)
			(stroke
				(width 0.1)
				(type default)
			)
			(layer "F.Fab")
		)
		(fp_line
			(start 0.12065 -0.2794)
			(end 0.12065 -0.3048)
			(stroke
				(width 0.1)
				(type default)
			)
			(layer "F.Fab")
		)
		(fp_line
			(start 0.12065 -0.3048)
			(end 0.67945 -0.3048)
			(stroke
				(width 0.1)
				(type default)
			)
			(layer "F.Fab")
		)
		(fp_line
			(start 0.120396 0.3048)
			(end 0.120396 0.2794)
			(stroke
				(width 0.1)
				(type default)
			)
			(layer "F.Fab")
		)
		(fp_line
			(start 0.120396 0.2794)
			(end -0.12065 0.2794)
			(stroke
				(width 0.1)
				(type default)
			)
			(layer "F.Fab")
		)
		(fp_line
			(start -0.12065 0.3048)
			(end -0.67945 0.3048)
			(stroke
				(width 0.1)
				(type default)
			)
			(layer "F.Fab")
		)
		(fp_line
			(start -0.12065 0.2794)
			(end -0.12065 0.3048)
			(stroke
				(width 0.1)
				(type default)
			)
			(layer "F.Fab")
		)
		(fp_line
			(start -0.12065 -0.2794)
			(end 0.12065 -0.2794)
			(stroke
				(width 0.1)
				(type default)
			)
			(layer "F.Fab")
		)
		(fp_line
			(start -0.12065 -0.305054)
			(end -0.12065 -0.2794)
			(stroke
				(width 0.1)
				(type default)
			)
			(layer "F.Fab")
		)
		(fp_line
			(start -0.67945 0.3048)
			(end -0.67945 -0.305054)
			(stroke
				(width 0.1)
				(type default)
			)
			(layer "F.Fab")
		)
		(fp_line
			(start -0.67945 -0.305054)
			(end -0.12065 -0.305054)
			(stroke
				(width 0.1)
				(type default)
			)
			(layer "F.Fab")
		)
		(pad "1" smd circle
			(at -0.40005 0 180)
			(size 0 0)
			(layers "F.Cu" "F.Mask" "F.Paste")
			(net "HSC_IMON")
		)
		(pad "2" smd circle
			(at 0.40005 0 180)
			(size 0 0)
			(layers "F.Cu" "F.Mask" "F.Paste")
			(net "AGND_HSC")
		)
	)
)
